# T6G (Grand Teton) — schematic netlist excerpt (pin names and nets, part order shuffled) for the footprints in the layout excerpt that follows; sources: Cadence DE-HDL packaged netlist, KiCad conversion of 04192023_DAF0TMB3IC0_F0TG_MB_C_brd_V02_OCP.brd

PC6904  Q_CAP  22UF 16V 20% X6S  pkg C0805  page 361 : A = SW_P12V_AUX_P1V8_RETIMER_CPU1_FLT ; B = GND
R1170  Q_RES  0 5% CHIP  pkg 0402LF  page 142 : A = OCP_V3_2_P3V3_PLD_PWRGD ; B = OCP_V3_2_P3V3_PLD_R_PWRGD

(kicad_pcb
	(version 20260206)
	(generator "pcbnew")
	(generator_version "10.0")
	(general
		(thickness 1.6)
		(legacy_teardrops no)
	)
	(paper "A4")
	(title_block
		(title "04192023_DAF0TMB3IC0_F0TG_MB_C_brd_V02_OCP.brd")
		(comment 1 "Grand Teton / footprints 1547-1548 of 8354")
	)
	(layers
		(0 "F.Cu" signal "TOP")
		(4 "In1.Cu" signal "GND")
		(6 "In2.Cu" signal "IN1")
		(8 "In3.Cu" signal "GND1")
		(10 "In4.Cu" signal "IN2")
		(12 "In5.Cu" signal "GND2")
		(14 "In6.Cu" signal "IN3")
		(16 "In7.Cu" signal "GND3")
		(18 "In8.Cu" signal "VCC")
		(20 "In9.Cu" signal "VCC1")
		(22 "In10.Cu" signal "GND4")
		(24 "In11.Cu" signal "IN4")
		(26 "In12.Cu" signal "GND5")
		(28 "In13.Cu" signal "IN5")
		(30 "In14.Cu" signal "GND6")
		(32 "In15.Cu" signal "IN6")
		(34 "In16.Cu" signal "GND7")
		(2 "B.Cu" signal "BOTTOM")
		(9 "F.Adhes" user "F.Adhesive")
		(11 "B.Adhes" user "B.Adhesive")
		(13 "F.Paste" user "Package Geometry/Pastemask Top")
		(15 "B.Paste" user "Package Geometry/Pastemask Bottom")
		(5 "F.SilkS" user "Ref Des/Silkscreen Top")
		(7 "B.SilkS" user "Ref Des/Silkscreen Bottom")
		(1 "F.Mask" user "Board Geometry/Soldermask Top")
		(3 "B.Mask" user "Board Geometry/Soldermask Bottom")
		(17 "Dwgs.User" user "User.Drawings")
		(19 "Cmts.User" user "User.Comments")
		(21 "Eco1.User" user "User.Eco1")
		(23 "Eco2.User" user "User.Eco2")
		(25 "Edge.Cuts" user "Board Geometry/Outline")
		(27 "Margin" user)
		(31 "F.CrtYd" user "Package Geometry/Place Bound Top")
		(29 "B.CrtYd" user "Package Geometry/Place Bound Bottom")
		(35 "F.Fab" user "Ref Des/Assembly Top")
		(33 "B.Fab" user "Ref Des/Assembly Bottom")
	)
	(footprint ""
		(layer "F.Cu")
		(at 87.922862 -69.059044 90)
		(property "Reference" "R1170"
			(at 0 0 90)
			(layer "F.SilkS")
			(hide yes)
			(effects
				(font
					(size 1.27 1.27)
				)
			)
		)
		(property "Value" ""
			(at 0 0 90)
			(layer "F.Fab")
			(effects
				(font
					(size 1.27 1.27)
				)
			)
		)
		(duplicate_pad_numbers_are_jumpers no)
		(fp_line
			(start 0.7874 -0.4064)
			(end 0.7874 0.4064)
			(stroke
				(width 0.1524)
				(type default)
			)
			(layer "F.SilkS")
		)
		(fp_line
			(start -0.7874 -0.4064)
			(end 0.7874 -0.4064)
			(stroke
				(width 0.1524)
				(type default)
			)
			(layer "F.SilkS")
		)
		(fp_line
			(start 0.7874 0.4064)
			(end -0.7874 0.4064)
			(stroke
				(width 0.1524)
				(type default)
			)
			(layer "F.SilkS")
		)
		(fp_line
			(start -0.7874 0.4064)
			(end -0.7874 -0.4064)
			(stroke
				(width 0.1524)
				(type default)
			)
			(layer "F.SilkS")
		)
		(fp_line
			(start -0.12065 -0.305054)
			(end -0.12065 -0.2794)
			(stroke
				(width 0.1)
				(type default)
			)
			(layer "F.Fab")
		)
		(fp_line
			(start -0.67945 -0.305054)
			(end -0.12065 -0.305054)
			(stroke
				(width 0.1)
				(type default)
			)
			(layer "F.Fab")
		)
		(fp_line
			(start 0.67945 -0.3048)
			(end 0.67945 0.3048)
			(stroke
				(width 0.1)
				(type default)
			)
			(layer "F.Fab")
		)
		(fp_line
			(start 0.12065 -0.3048)
			(end 0.67945 -0.3048)
			(stroke
				(width 0.1)
				(type default)
			)
			(layer "F.Fab")
		)
		(fp_line
			(start 0.12065 -0.2794)
			(end 0.12065 -0.3048)
			(stroke
				(width 0.1)
				(type default)
			)
			(layer "F.Fab")
		)
		(fp_line
			(start -0.12065 -0.2794)
			(end 0.12065 -0.2794)
			(stroke
				(width 0.1)
				(type default)
			)
			(layer "F.Fab")
		)
		(fp_line
			(start 0.120396 0.2794)
			(end -0.12065 0.2794)
			(stroke
				(width 0.1)
				(type default)
			)
			(layer "F.Fab")
		)
		(fp_line
			(start -0.12065 0.2794)
			(end -0.12065 0.3048)
			(stroke
				(width 0.1)
				(type default)
			)
			(layer "F.Fab")
		)
		(fp_line
			(start 0.67945 0.3048)
			(end 0.120396 0.3048)
			(stroke
				(width 0.1)
				(type default)
			)
			(layer "F.Fab")
		)
		(fp_line
			(start 0.120396 0.3048)
			(end 0.120396 0.2794)
			(stroke
				(width 0.1)
				(type default)
			)
			(layer "F.Fab")
		)
		(fp_line
			(start -0.12065 0.3048)
			(end -0.67945 0.3048)
			(stroke
				(width 0.1)
				(type default)
			)
			(layer "F.Fab")
		)
		(fp_line
			(start -0.67945 0.3048)
			(end -0.67945 -0.305054)
			(stroke
				(width 0.1)
				(type default)
			)
			(layer "F.Fab")
		)
		(pad "1" smd circle
			(at -0.40005 0 90)
			(size 0 0)
			(layers "F.Cu" "F.Mask" "F.Paste")
			(net "OCP_V3_2_P3V3_PLD_PWRGD")
		)
		(pad "2" smd circle
			(at 0.40005 0 90)
			(size 0 0)
			(layers "F.Cu" "F.Mask" "F.Paste")
			(net "OCP_V3_2_P3V3_PLD_R_PWRGD")
		)
	)
	(footprint ""
		(layer "F.Cu")
		(at 229.87 -287.376362 180)
		(property "Reference" "PC6904"
			(at 0 0 180)
			(layer "F.SilkS")
			(hide yes)
			(effects
				(font
					(size 1.27 1.27)
				)
			)
		)
		(property "Value" ""
			(at 0 0 180)
			(layer "F.Fab")
			(effects
				(font
					(size 1.27 1.27)
				)
			)
		)
		(duplicate_pad_numbers_are_jumpers no)
		(fp_line
			(start 1.524 0.762)
			(end -1.524 0.762)
			(stroke
				(width 0.1524)
				(type default)
			)
			(layer "F.SilkS")
		)
		(fp_line
			(start 1.524 -0.762)
			(end 1.524 0.762)
			(stroke
				(width 0.1524)
				(type default)
			)
			(layer "F.SilkS")
		)
		(fp_line
			(start -1.524 0.762)
			(end -1.524 -0.762)
			(stroke
				(width 0.1524)
				(type default)
			)
			(layer "F.SilkS")
		)
		(fp_line
			(start -1.524 -0.762)
			(end 1.524 -0.762)
			(stroke
				(width 0.1524)
				(type default)
			)
			(layer "F.SilkS")
		)
		(fp_line
			(start 1.1049 0.724916)
			(end 1.1049 -0.724916)
			(stroke
				(width 0.1)
				(type default)
			)
			(layer "F.Fab")
		)
		(fp_line
			(start 1.1049 -0.724916)
			(end -1.1049 -0.724916)
			(stroke
				(width 0.1)
				(type default)
			)
			(layer "F.Fab")
		)
		(fp_line
			(start -1.1049 0.724916)
			(end 1.1049 0.724916)
			(stroke
				(width 0.1)
				(type default)
			)
			(layer "F.Fab")
		)
		(fp_line
			(start -1.1049 -0.724916)
			(end -1.1049 0.724916)
			(stroke
				(width 0.1)
				(type default)
			)
			(layer "F.Fab")
		)
		(pad "1" smd rect
			(at -0.889 0)
			(size 1.016 1.27)
			(layers "F.Cu" "F.Mask" "F.Paste")
			(net "SW_P12V_AUX_P1V8_RETIMER_CPU1_FLT")
		)
		(pad "2" smd rect
			(at 0.889 0)
			(size 1.016 1.27)
			(layers "F.Cu" "F.Mask" "F.Paste")
			(net "GND")
		)
	)
)
